# BASEBOARD_FAB2 (Tioga Pass) — schematic netlist excerpt (pin names and nets, part order shuffled) for the footprints in the layout excerpt that follows; sources: Cadence DE-HDL packaged netlist, KiCad conversion of Wiwynn_Tioga_Pass_MB.brd

R8G4  RES  20.0 1% CHIP  pkg 0402  page 159 : A = SMB_OCP_LAN_STBY_LVC3_SCL_R ; B = SMB_OCP_LAN_STBY_LVC3_SCL

Q12W3  BSL308C-H6327-GP  pkg DISCRET-GB1  page 197
  \gate#1\  = PWRGD_PVDDQ_GHJ
  \source#2\  = P12V_NVDIMM_GHJ
  \gate#3\  = PWRGD_PVDDQ_GHJ_N
  \drain#4\  = P12V_NVDIMM_GHJ_D
  \source#5\  = GND
  \drain#6\  = PWRGD_PVDDQ_GHJ_N

(kicad_pcb
	(version 20260206)
	(generator "pcbnew")
	(generator_version "10.0")
	(general
		(thickness 1.6)
		(legacy_teardrops no)
	)
	(paper "A4")
	(title_block
		(title "Wiwynn_Tioga_Pass_MB.brd")
		(comment 1 "Tioga Pass / footprints 704-705 of 4770")
	)
	(layers
		(0 "F.Cu" signal "TOP")
		(4 "In1.Cu" signal "L2GND")
		(6 "In2.Cu" signal "L3")
		(8 "In3.Cu" signal "L4GND")
		(10 "In4.Cu" signal "L5")
		(12 "In5.Cu" signal "L6GND")
		(14 "In6.Cu" signal "L7VCC")
		(16 "In7.Cu" signal "L8VCC")
		(18 "In8.Cu" signal "L9GND")
		(20 "In9.Cu" signal "L10")
		(22 "In10.Cu" signal "L11GND")
		(24 "In11.Cu" signal "L12")
		(26 "In12.Cu" signal "L13GND")
		(2 "B.Cu" signal "BOTTOM")
		(9 "F.Adhes" user "F.Adhesive")
		(11 "B.Adhes" user "B.Adhesive")
		(13 "F.Paste" user "Package Geometry/Pastemask Top")
		(15 "B.Paste" user "Package Geometry/Pastemask Bottom")
		(5 "F.SilkS" user "Ref Des/Silkscreen Top")
		(7 "B.SilkS" user "Ref Des/Silkscreen Bottom")
		(1 "F.Mask" user "Board Geometry/Soldermask Top")
		(3 "B.Mask" user "Board Geometry/Soldermask Bottom")
		(17 "Dwgs.User" user "User.Drawings")
		(19 "Cmts.User" user "User.Comments")
		(21 "Eco1.User" user "User.Eco1")
		(23 "Eco2.User" user "User.Eco2")
		(25 "Edge.Cuts" user "Board Geometry/Outline")
		(27 "Margin" user)
		(31 "F.CrtYd" user "Package Geometry/Place Bound Top")
		(29 "B.CrtYd" user "Package Geometry/Place Bound Bottom")
		(35 "F.Fab" user "Ref Des/Assembly Top")
		(33 "B.Fab" user "Ref Des/Assembly Bottom")
	)
	(footprint ""
		(layer "F.Cu")
		(at 29.213556 -31.141162 90)
		(property "Reference" "Q12W3"
			(at 0 0 90)
			(layer "F.SilkS")
			(hide yes)
			(effects
				(font
					(size 1.27 1.27)
				)
			)
		)
		(property "Value" "*"
			(at -4.572 -7.6835 90)
			(unlocked yes)
			(layer "F.Fab")
			(hide yes)
			(effects
				(font
					(size 1.27 1.016)
					(thickness 0.1524)
				)
			)
		)
		(property "Device Type" "BSL308C-H6327-GP_DISCRET-GB1-BA"
			(at -4.572 -9.2075 90)
			(unlocked yes)
			(layer "F.Fab")
			(hide yes)
			(effects
				(font
					(size 1.27 1.016)
					(thickness 0.1524)
				)
			)
		)
		(duplicate_pad_numbers_are_jumpers no)
		(fp_line
			(start 1.102868 -0.081534)
			(end 1.102868 0.081534)
			(stroke
				(width 0.1524)
				(type default)
			)
			(layer "F.SilkS")
		)
		(fp_line
			(start -1.8796 -0.081534)
			(end 1.102868 -0.081534)
			(stroke
				(width 0.1524)
				(type default)
			)
			(layer "F.SilkS")
		)
		(fp_line
			(start -1.8796 -0.081534)
			(end -1.524 0)
			(stroke
				(width 0.1524)
				(type default)
			)
			(layer "F.SilkS")
		)
		(fp_line
			(start -1.524 0)
			(end -1.8796 0.081534)
			(stroke
				(width 0.1524)
				(type default)
			)
			(layer "F.SilkS")
		)
		(fp_line
			(start 1.102868 0.081534)
			(end -1.8796 0.081534)
			(stroke
				(width 0.1524)
				(type default)
			)
			(layer "F.SilkS")
		)
		(fp_line
			(start -1.8796 0.081534)
			(end -1.8796 -0.081534)
			(stroke
				(width 0.1524)
				(type default)
			)
			(layer "F.SilkS")
		)
		(fp_line
			(start -1.7018 0.3048)
			(end -1.7018 1.8796)
			(stroke
				(width 0.508)
				(type default)
			)
			(layer "F.SilkS")
		)
		(fp_poly
			(pts
				(xy -1.179068 0.081534) (xy -1.179068 -0.081534) (xy 1.102868 -0.081534) (xy 1.102868 0.081534)
			)
			(stroke
				(width 0)
				(type default)
			)
			(fill yes)
			(layer "F.SilkS")
		)
		(fp_rect
			(start -1.4478 1.2446)
			(end 1.4478 -1.2446)
			(stroke
				(width 0)
				(type default)
			)
			(fill no)
			(layer "F.CrtYd")
		)
		(fp_poly
			(pts
				(xy -1.4478 -1.23952) (xy -1.9558 -1.23952) (xy -1.9558 2.1336) (xy 1.9558 2.1336) (xy 1.9558 -2.1336)
				(xy -1.9558 -2.1336) (xy -1.9558 -1.2446) (xy 1.4478 -1.2446) (xy 1.4478 1.2446) (xy -1.4478 1.2446)
			)
			(stroke
				(width 0)
				(type default)
			)
			(fill no)
			(layer "F.CrtYd")
		)
		(fp_rect
			(start -1.9558 2.1336)
			(end 1.9558 -2.1336)
			(stroke
				(width 0)
				(type default)
			)
			(fill no)
			(layer "F.Fab")
		)
		(pad "1" smd rect
			(at -0.950468 0.995934 90)
			(size 0.4572 1.27)
			(layers "F.Cu" "F.Mask" "F.Paste")
			(net "PWRGD_PVDDQ_GHJ")
		)
		(pad "2" smd rect
			(at 0 0.995934 90)
			(size 0.4572 1.27)
			(layers "F.Cu" "F.Mask" "F.Paste")
			(net "P12V_NVDIMM_GHJ")
		)
		(pad "3" smd rect
			(at 0.950468 0.995934 90)
			(size 0.4572 1.27)
			(layers "F.Cu" "F.Mask" "F.Paste")
			(net "PWRGD_PVDDQ_GHJ_N")
		)
		(pad "4" smd rect
			(at 0.950468 -0.995934 90)
			(size 0.4572 1.27)
			(layers "F.Cu" "F.Mask" "F.Paste")
			(net "P12V_NVDIMM_GHJ_D")
		)
		(pad "5" smd rect
			(at 0 -0.995934 90)
			(size 0.4572 1.27)
			(layers "F.Cu" "F.Mask" "F.Paste")
			(net "GND")
		)
		(pad "6" smd rect
			(at -0.950468 -0.995934 90)
			(size 0.4572 1.27)
			(layers "F.Cu" "F.Mask" "F.Paste")
			(net "PWRGD_PVDDQ_GHJ_N")
		)
	)
	(footprint ""
		(layer "F.Cu")
		(at 399.763996 -35.803586 -90)
		(property "Reference" "R8G4"
			(at 0 0 270)
			(layer "F.SilkS")
			(hide yes)
			(effects
				(font
					(size 1.27 1.27)
				)
			)
		)
		(property "Value" ""
			(at 0 0 270)
			(layer "F.Fab")
			(effects
				(font
					(size 1.27 1.27)
				)
			)
		)
		(duplicate_pad_numbers_are_jumpers no)
		(fp_poly
			(pts
				(xy -0.2794 -0.1016) (xy 0.2794 -0.1016) (xy 0.2794 0.9906) (xy -0.2794 0.9906)
			)
			(stroke
				(width 0)
				(type default)
			)
			(fill no)
			(layer "F.CrtYd")
		)
		(fp_line
			(start -0.2794 0.9906)
			(end 0.2794 0.9906)
			(stroke
				(width 0.1)
				(type default)
			)
			(layer "F.Fab")
		)
		(fp_line
			(start 0.2794 0.9906)
			(end 0.2794 -0.1016)
			(stroke
				(width 0.1)
				(type default)
			)
			(layer "F.Fab")
		)
		(fp_line
			(start -0.2794 -0.1016)
			(end -0.2794 0.9906)
			(stroke
				(width 0.1)
				(type default)
			)
			(layer "F.Fab")
		)
		(fp_line
			(start 0.2794 -0.1016)
			(end -0.2794 -0.1016)
			(stroke
				(width 0.1)
				(type default)
			)
			(layer "F.Fab")
		)
		(pad "1" smd rect
			(at 0 0 270)
			(size 0.508 0.508)
			(layers "F.Cu" "F.Mask" "F.Paste")
			(net "SMB_OCP_LAN_STBY_LVC3_SCL_R")
		)
		(pad "2" smd rect
			(at 0 0.889 270)
			(size 0.508 0.508)
			(layers "F.Cu" "F.Mask" "F.Paste")
			(net "SMB_OCP_LAN_STBY_LVC3_SCL")
		)
		(zone
			(layer "F.Cu")
			(hatch none 0.5)
			(connect_pads
				(clearance 0)
			)
			(min_thickness 0.25)
			(keepout
				(tracks not_allowed)
				(vias allowed)
				(pads allowed)
				(copperpour not_allowed)
				(footprints allowed)
			)
			(placement
				(enabled no)
				(sheetname "")
			)
			(fill
				(thermal_gap 0.5)
				(thermal_bridge_width 0.5)
				(island_removal_mode 0)
			)
			(polygon
				(pts
					(xy 399.128996 -36.057586) (xy 399.128996 -35.549586) (xy 399.509996 -35.549586) (xy 399.509996 -36.057586)
				)
			)
		)
		(zone
			(layer "F.Cu")
			(hatch none 0.5)
			(connect_pads
				(clearance 0)
			)
			(min_thickness 0.25)
			(keepout
				(tracks allowed)
				(vias not_allowed)
				(pads allowed)
				(copperpour not_allowed)
				(footprints allowed)
			)
			(placement
				(enabled no)
				(sheetname "")
			)
			(fill
				(thermal_gap 0.5)
				(thermal_bridge_width 0.5)
				(island_removal_mode 0)
			)
			(polygon
				(pts
					(xy 399.509996 -36.057586) (xy 399.509996 -35.549586) (xy 399.128996 -35.549586) (xy 399.128996 -36.057586)
				)
			)
		)
	)
)
